(kicad_pcb
	(version 20260206)
	(generator "pcbnew")
	(generator_version "10.0")
	(general
		(thickness 1.6)
		(legacy_teardrops no)
	)
	(paper "A4")
	(title_block
		(title "9054_F0T_PDB_BD_GPU_F_V04_1213_1550_OCP.brd")
		(comment 1 "Grand Teton / footprints 241-246 of 608")
	)
	(layers
		(0 "F.Cu" signal "TOP")
		(4 "In1.Cu" signal "GND")
		(6 "In2.Cu" signal "IN1")
		(8 "In3.Cu" signal "GND1")
		(10 "In4.Cu" signal "VCC")
		(12 "In5.Cu" signal "VCC1")
		(14 "In6.Cu" signal "GND2")
		(16 "In7.Cu" signal "IN2")
		(18 "In8.Cu" signal "GND3")
		(2 "B.Cu" signal "BOTTOM")
		(9 "F.Adhes" user "F.Adhesive")
		(11 "B.Adhes" user "B.Adhesive")
		(13 "F.Paste" user "Package Geometry/Pastemask Top")
		(15 "B.Paste" user "Package Geometry/Pastemask Bottom")
		(5 "F.SilkS" user "Ref Des/Silkscreen Top")
		(7 "B.SilkS" user "Ref Des/Silkscreen Bottom")
		(1 "F.Mask" user "Board Geometry/Soldermask Top")
		(3 "B.Mask" user "Board Geometry/Soldermask Bottom")
		(17 "Dwgs.User" user "User.Drawings")
		(19 "Cmts.User" user "User.Comments")
		(21 "Eco1.User" user "User.Eco1")
		(23 "Eco2.User" user "User.Eco2")
		(25 "Edge.Cuts" user "Board Geometry/Outline")
		(27 "Margin" user)
		(31 "F.CrtYd" user "Package Geometry/Place Bound Top")
		(29 "B.CrtYd" user "Package Geometry/Place Bound Bottom")
		(35 "F.Fab" user "Ref Des/Assembly Top")
		(33 "B.Fab" user "Ref Des/Assembly Bottom")
	)
	(footprint ""
		(layer "F.Cu")
		(at 442.849 -99.695 180)
		(property "Reference" "PC138"
			(at 3.302 4.29133 0)
			(unlocked yes)
			(layer "F.SilkS")
			(effects
				(font
					(size 0.7874 0.5842)
					(thickness 0.1524)
				)
				(justify left)
			)
		)
		(property "Value" ""
			(at 0 0 180)
			(layer "F.Fab")
			(effects
				(font
					(size 1.27 1.27)
				)
			)
		)
		(duplicate_pad_numbers_are_jumpers no)
		(fp_line
			(start 3.400044 3.400044)
			(end -2.146046 3.400044)
			(stroke
				(width 0.1524)
				(type default)
			)
			(layer "F.SilkS")
		)
		(fp_line
			(start 3.400044 0.9398)
			(end 3.400044 3.400044)
			(stroke
				(width 0.1524)
				(type default)
			)
			(layer "F.SilkS")
		)
		(fp_line
			(start 3.400044 -0.9398)
			(end 3.400044 -3.400044)
			(stroke
				(width 0.1524)
				(type default)
			)
			(layer "F.SilkS")
		)
		(fp_line
			(start 3.400044 -3.400044)
			(end -2.146046 -3.400044)
			(stroke
				(width 0.1524)
				(type default)
			)
			(layer "F.SilkS")
		)
		(fp_line
			(start -2.146046 3.400044)
			(end -3.400044 2.146046)
			(stroke
				(width 0.1524)
				(type default)
			)
			(layer "F.SilkS")
		)
		(fp_line
			(start -2.146046 -3.400044)
			(end -3.400044 -2.146046)
			(stroke
				(width 0.1524)
				(type default)
			)
			(layer "F.SilkS")
		)
		(fp_line
			(start -3.400044 2.146046)
			(end -3.400044 0.9398)
			(stroke
				(width 0.1524)
				(type default)
			)
			(layer "F.SilkS")
		)
		(fp_line
			(start -3.400044 -2.146046)
			(end -3.400044 -0.9398)
			(stroke
				(width 0.1524)
				(type default)
			)
			(layer "F.SilkS")
		)
		(fp_line
			(start 3.400044 3.400044)
			(end 3.400044 -3.400044)
			(stroke
				(width 0.1)
				(type default)
			)
			(layer "F.Fab")
		)
		(fp_line
			(start 3.400044 -3.400044)
			(end -3.400044 -3.400044)
			(stroke
				(width 0.1)
				(type default)
			)
			(layer "F.Fab")
		)
		(fp_line
			(start -3.400044 3.400044)
			(end 3.400044 3.400044)
			(stroke
				(width 0.1)
				(type default)
			)
			(layer "F.Fab")
		)
		(fp_line
			(start -3.400044 -3.400044)
			(end -3.400044 3.400044)
			(stroke
				(width 0.1)
				(type default)
			)
			(layer "F.Fab")
		)
		(pad "1" smd rect
			(at -2.70002 0 90)
			(size 1.6002 3.5052)
			(layers "F.Cu" "F.Mask" "F.Paste")
			(net "SW_P3V3_HPDB_FLT")
		)
		(pad "2" smd rect
			(at 2.70002 0 90)
			(size 1.6002 3.5052)
			(layers "F.Cu" "F.Mask" "F.Paste")
			(net "GND")
		)
	)
	(footprint ""
		(layer "F.Cu")
		(at 178.0794 -49.149)
		(property "Reference" "U25"
			(at 2.0066 -1.24333 0)
			(unlocked yes)
			(layer "F.SilkS")
			(effects
				(font
					(size 0.7874 0.5842)
					(thickness 0.1524)
				)
				(justify left)
			)
		)
		(property "Value" ""
			(at 0 0 0)
			(layer "F.Fab")
			(effects
				(font
					(size 1.27 1.27)
				)
			)
		)
		(duplicate_pad_numbers_are_jumpers no)
		(fp_line
			(start -1.603248 -1.500124)
			(end 1.603248 -1.500124)
			(stroke
				(width 0.1524)
				(type default)
			)
			(layer "F.SilkS")
		)
		(fp_line
			(start -1.603248 1.500124)
			(end -1.603248 -1.500124)
			(stroke
				(width 0.1524)
				(type default)
			)
			(layer "F.SilkS")
		)
		(fp_line
			(start 1.603248 -1.500124)
			(end 1.603248 1.500124)
			(stroke
				(width 0.1524)
				(type default)
			)
			(layer "F.SilkS")
		)
		(fp_line
			(start 1.603248 1.500124)
			(end -1.603248 1.500124)
			(stroke
				(width 0.1524)
				(type default)
			)
			(layer "F.SilkS")
		)
		(fp_line
			(start -1.249934 -1.169924)
			(end -1.249934 -0.729996)
			(stroke
				(width 0.1)
				(type default)
			)
			(layer "F.Fab")
		)
		(fp_line
			(start -1.249934 -0.729996)
			(end -0.6985 -0.729996)
			(stroke
				(width 0.1)
				(type default)
			)
			(layer "F.Fab")
		)
		(fp_line
			(start -1.249934 0.729996)
			(end -1.249934 1.169924)
			(stroke
				(width 0.1)
				(type default)
			)
			(layer "F.Fab")
		)
		(fp_line
			(start -1.249934 1.169924)
			(end -0.700024 1.169924)
			(stroke
				(width 0.1)
				(type default)
			)
			(layer "F.Fab")
		)
		(fp_line
			(start -0.700024 -1.500124)
			(end -0.700024 -1.169924)
			(stroke
				(width 0.1)
				(type default)
			)
			(layer "F.Fab")
		)
		(fp_line
			(start -0.700024 -1.169924)
			(end -1.249934 -1.169924)
			(stroke
				(width 0.1)
				(type default)
			)
			(layer "F.Fab")
		)
		(fp_line
			(start -0.700024 1.169924)
			(end -0.700024 1.500124)
			(stroke
				(width 0.1)
				(type default)
			)
			(layer "F.Fab")
		)
		(fp_line
			(start -0.700024 1.500124)
			(end 0.700024 1.500124)
			(stroke
				(width 0.1)
				(type default)
			)
			(layer "F.Fab")
		)
		(fp_line
			(start -0.6985 -0.729996)
			(end -0.6985 0.729996)
			(stroke
				(width 0.1)
				(type default)
			)
			(layer "F.Fab")
		)
		(fp_line
			(start -0.6985 0.729996)
			(end -1.249934 0.729996)
			(stroke
				(width 0.1)
				(type default)
			)
			(layer "F.Fab")
		)
		(fp_line
			(start 0.700024 -1.500124)
			(end -0.700024 -1.500124)
			(stroke
				(width 0.1)
				(type default)
			)
			(layer "F.Fab")
		)
		(fp_line
			(start 0.700024 -0.219964)
			(end 0.700024 -1.500124)
			(stroke
				(width 0.1)
				(type default)
			)
			(layer "F.Fab")
		)
		(fp_line
			(start 0.700024 0.219964)
			(end 1.249934 0.219964)
			(stroke
				(width 0.1)
				(type default)
			)
			(layer "F.Fab")
		)
		(fp_line
			(start 0.700024 1.500124)
			(end 0.700024 0.219964)
			(stroke
				(width 0.1)
				(type default)
			)
			(layer "F.Fab")
		)
		(fp_line
			(start 1.249934 -0.219964)
			(end 0.700024 -0.219964)
			(stroke
				(width 0.1)
				(type default)
			)
			(layer "F.Fab")
		)
		(fp_line
			(start 1.249934 0.219964)
			(end 1.249934 -0.219964)
			(stroke
				(width 0.1)
				(type default)
			)
			(layer "F.Fab")
		)
		(fp_rect
			(start -0.700024 1.500124)
			(end 0.700024 -1.500124)
			(stroke
				(width 0)
				(type default)
			)
			(fill no)
			(layer "F.Fab")
		)
		(pad "D" smd rect
			(at 0.999998 0 270)
			(size 0.8128 0.9144)
			(layers "F.Cu" "F.Mask" "F.Paste")
			(net "GPU_HSC2_BUF_EN")
		)
		(pad "G" smd rect
			(at -0.999998 -0.94996 270)
			(size 0.8128 0.9144)
			(layers "F.Cu" "F.Mask" "F.Paste")
			(net "GPU_HSC2_BUF_EN_N")
		)
		(pad "S" smd rect
			(at -0.999998 0.94996 270)
			(size 0.8128 0.9144)
			(layers "F.Cu" "F.Mask" "F.Paste")
			(net "GND")
		)
	)
	(footprint ""
		(layer "F.Cu")
		(at 414.8582 -20.2692)
		(property "Reference" "D5"
			(at -3.429 -2.29743 0)
			(unlocked yes)
			(layer "F.SilkS")
			(effects
				(font
					(size 0.7874 0.5842)
					(thickness 0.1524)
				)
				(justify left)
			)
		)
		(property "Value" ""
			(at 0 0 0)
			(layer "F.Fab")
			(effects
				(font
					(size 1.27 1.27)
				)
			)
		)
		(duplicate_pad_numbers_are_jumpers no)
		(fp_line
			(start -3.400044 -1.459992)
			(end 4.107942 -1.459992)
			(stroke
				(width 0.1524)
				(type default)
			)
			(layer "F.SilkS")
		)
		(fp_line
			(start -3.400044 1.459992)
			(end -3.400044 -1.459992)
			(stroke
				(width 0.1524)
				(type default)
			)
			(layer "F.SilkS")
		)
		(fp_line
			(start 4.107942 -1.459992)
			(end 4.107942 1.459992)
			(stroke
				(width 0.1524)
				(type default)
			)
			(layer "F.SilkS")
		)
		(fp_line
			(start 4.107942 1.459992)
			(end -3.400044 1.459992)
			(stroke
				(width 0.1524)
				(type default)
			)
			(layer "F.SilkS")
		)
		(fp_poly
			(pts
				(xy 4.107942 -1.459992) (xy 4.107942 1.459992) (xy 3.308096 1.459992) (xy 3.308096 -1.459992)
			)
			(stroke
				(width 0)
				(type default)
			)
			(fill yes)
			(layer "F.SilkS")
		)
		(fp_line
			(start -2.29997 -1.459992)
			(end 2.29997 -1.459992)
			(stroke
				(width 0.1)
				(type default)
			)
			(layer "F.Fab")
		)
		(fp_line
			(start -2.29997 1.459992)
			(end -2.29997 -1.459992)
			(stroke
				(width 0.1)
				(type default)
			)
			(layer "F.Fab")
		)
		(fp_line
			(start 2.29997 -1.459992)
			(end 2.29997 1.459992)
			(stroke
				(width 0.1)
				(type default)
			)
			(layer "F.Fab")
		)
		(fp_line
			(start 2.29997 1.459992)
			(end -2.29997 1.459992)
			(stroke
				(width 0.1)
				(type default)
			)
			(layer "F.Fab")
		)
		(fp_text user "+"
			(at -5.842 -0.19685 0)
			(unlocked yes)
			(layer "F.SilkS")
			(effects
				(font
					(size 1.905 1.4224)
					(thickness 0.1524)
				)
				(justify left)
			)
		)
		(fp_text user "-"
			(at 5.4102 0.29845 180)
			(unlocked yes)
			(layer "F.SilkS")
			(effects
				(font
					(size 1.905 1.4224)
					(thickness 0.1524)
				)
				(justify left)
			)
		)
		(fp_text user "+"
			(at -4.7752 -0.12065 0)
			(unlocked yes)
			(layer "F.Fab")
			(effects
				(font
					(size 1.905 1.4224)
					(thickness 0.1524)
				)
				(justify left)
			)
		)
		(fp_text user "-"
			(at 5.4102 0.29845 180)
			(unlocked yes)
			(layer "F.Fab")
			(effects
				(font
					(size 1.905 1.4224)
					(thickness 0.1524)
				)
				(justify left)
			)
		)
		(pad "A" smd rect
			(at -1.999996 0 90)
			(size 1.7018 2.5146)
			(layers "F.Cu" "F.Mask" "F.Paste")
			(net "GND")
		)
		(pad "C" smd rect
			(at 1.999996 0 90)
			(size 1.7018 2.5146)
			(layers "F.Cu" "F.Mask" "F.Paste")
			(net "P12V_FAN_LED")
		)
	)
	(footprint ""
		(layer "F.Cu")
		(at 387.223 -25.527 90)
		(property "Reference" "PR102"
			(at 0 0 90)
			(layer "F.SilkS")
			(hide yes)
			(effects
				(font
					(size 1.27 1.27)
				)
			)
		)
		(property "Value" ""
			(at 0 0 90)
			(layer "F.Fab")
			(effects
				(font
					(size 1.27 1.27)
				)
			)
		)
		(duplicate_pad_numbers_are_jumpers no)
		(fp_line
			(start 0.7874 -0.4064)
			(end 0.7874 0.4064)
			(stroke
				(width 0.1524)
				(type default)
			)
			(layer "F.SilkS")
		)
		(fp_line
			(start -0.7874 -0.4064)
			(end 0.7874 -0.4064)
			(stroke
				(width 0.1524)
				(type default)
			)
			(layer "F.SilkS")
		)
		(fp_line
			(start 0.7874 0.4064)
			(end -0.7874 0.4064)
			(stroke
				(width 0.1524)
				(type default)
			)
			(layer "F.SilkS")
		)
		(fp_line
			(start -0.7874 0.4064)
			(end -0.7874 -0.4064)
			(stroke
				(width 0.1524)
				(type default)
			)
			(layer "F.SilkS")
		)
		(fp_line
			(start -0.12065 -0.305054)
			(end -0.12065 -0.2794)
			(stroke
				(width 0.1)
				(type default)
			)
			(layer "F.Fab")
		)
		(fp_line
			(start -0.67945 -0.305054)
			(end -0.12065 -0.305054)
			(stroke
				(width 0.1)
				(type default)
			)
			(layer "F.Fab")
		)
		(fp_line
			(start 0.67945 -0.3048)
			(end 0.67945 0.3048)
			(stroke
				(width 0.1)
				(type default)
			)
			(layer "F.Fab")
		)
		(fp_line
			(start 0.12065 -0.3048)
			(end 0.67945 -0.3048)
			(stroke
				(width 0.1)
				(type default)
			)
			(layer "F.Fab")
		)
		(fp_line
			(start 0.12065 -0.2794)
			(end 0.12065 -0.3048)
			(stroke
				(width 0.1)
				(type default)
			)
			(layer "F.Fab")
		)
		(fp_line
			(start -0.12065 -0.2794)
			(end 0.12065 -0.2794)
			(stroke
				(width 0.1)
				(type default)
			)
			(layer "F.Fab")
		)
		(fp_line
			(start 0.120396 0.2794)
			(end -0.12065 0.2794)
			(stroke
				(width 0.1)
				(type default)
			)
			(layer "F.Fab")
		)
		(fp_line
			(start -0.12065 0.2794)
			(end -0.12065 0.3048)
			(stroke
				(width 0.1)
				(type default)
			)
			(layer "F.Fab")
		)
		(fp_line
			(start 0.67945 0.3048)
			(end 0.120396 0.3048)
			(stroke
				(width 0.1)
				(type default)
			)
			(layer "F.Fab")
		)
		(fp_line
			(start 0.120396 0.3048)
			(end 0.120396 0.2794)
			(stroke
				(width 0.1)
				(type default)
			)
			(layer "F.Fab")
		)
		(fp_line
			(start -0.12065 0.3048)
			(end -0.67945 0.3048)
			(stroke
				(width 0.1)
				(type default)
			)
			(layer "F.Fab")
		)
		(fp_line
			(start -0.67945 0.3048)
			(end -0.67945 -0.305054)
			(stroke
				(width 0.1)
				(type default)
			)
			(layer "F.Fab")
		)
		(pad "1" smd circle
			(at -0.40005 0 90)
			(size 0 0)
			(layers "F.Cu" "F.Mask" "F.Paste")
			(net "P52V_HS1_EN")
		)
		(pad "2" smd circle
			(at 0.40005 0 90)
			(size 0 0)
			(layers "F.Cu" "F.Mask" "F.Paste")
			(net "P52V_HS1_EN_DISCHARGE")
		)
	)
	(footprint ""
		(layer "F.Cu")
		(at 208.810098 -22.474936)
		(property "Reference" "H33"
			(at -1.9812 -4.079748 0)
			(unlocked yes)
			(layer "B.SilkS")
			(effects
				(font
					(size 0.7874 0.5842)
					(thickness 0.1524)
				)
				(justify left mirror)
			)
		)
		(property "Value" ""
			(at 0 0 0)
			(layer "F.Fab")
			(effects
				(font
					(size 1.27 1.27)
				)
			)
		)
		(duplicate_pad_numbers_are_jumpers no)
		(pad "1" thru_hole circle
			(at 0 0)
			(size 8.001 8.001)
			(drill 4.2418)
			(layers "*.Cu" "*.Mask")
			(remove_unused_layers no)
			(net "TP_H33")
			(clearance -1.6256)
			(padstack
				(mode front_inner_back)
				(layer "Inner"
					(shape circle)
					(size 6.0198 6.0198)
					(clearance -0.635)
				)
				(layer "B.Cu"
					(shape circle)
					(size 8.001 8.001)
					(clearance -1.6256)
				)
			)
		)
		(zone
			(layers "F.Cu" "B.Cu" "In1.Cu" "In2.Cu" "In3.Cu" "In4.Cu" "In5.Cu" "In6.Cu"
				"In7.Cu" "In8.Cu"
			)
			(hatch none 0.5)
			(connect_pads
				(clearance 0)
			)
			(min_thickness 0.25)
			(keepout
				(tracks not_allowed)
				(vias allowed)
				(pads allowed)
				(copperpour not_allowed)
				(footprints allowed)
			)
			(placement
				(enabled no)
				(sheetname "")
			)
			(fill
				(thermal_gap 0.5)
				(thermal_bridge_width 0.5)
				(island_removal_mode 0)
			)
			(polygon
				(pts
					(arc
						(start 212.320124 -22.474936)
						(mid 205.300072 -22.474936)
						(end 212.320124 -22.474936)
					)
				)
			)
		)
	)
	(footprint ""
		(layer "F.Cu")
		(at 397.637 -33.529778 90)
		(property "Reference" "PQ15"
			(at -9.680448 -5.0546 0)
			(unlocked yes)
			(layer "F.SilkS")
			(effects
				(font
					(size 0.7874 0.5842)
					(thickness 0.1524)
				)
				(justify left)
			)
		)
		(property "Value" ""
			(at 0 0 90)
			(layer "F.Fab")
			(effects
				(font
					(size 1.27 1.27)
				)
			)
		)
		(duplicate_pad_numbers_are_jumpers no)
		(fp_line
			(start 7.649972 -4.99999)
			(end 7.630414 -4.99999)
			(stroke
				(width 0.1524)
				(type default)
			)
			(layer "F.SilkS")
		)
		(fp_line
			(start 5.115814 -4.99999)
			(end -7.649972 -4.99999)
			(stroke
				(width 0.1524)
				(type default)
			)
			(layer "F.SilkS")
		)
		(fp_line
			(start -7.649972 -4.99999)
			(end -7.649972 -3.3274)
			(stroke
				(width 0.1524)
				(type default)
			)
			(layer "F.SilkS")
		)
		(fp_line
			(start -7.649972 -1.7526)
			(end -7.649972 1.7526)
			(stroke
				(width 0.1524)
				(type default)
			)
			(layer "F.SilkS")
		)
		(fp_line
			(start -7.649972 3.3274)
			(end -7.649972 4.99999)
			(stroke
				(width 0.1524)
				(type default)
			)
			(layer "F.SilkS")
		)
		(fp_line
			(start 7.649972 4.99999)
			(end 7.649972 -4.99999)
			(stroke
				(width 0.1524)
				(type default)
			)
			(layer "F.SilkS")
		)
		(fp_line
			(start 7.630414 4.99999)
			(end 7.649972 4.99999)
			(stroke
				(width 0.1524)
				(type default)
			)
			(layer "F.SilkS")
		)
		(fp_line
			(start -7.649972 4.99999)
			(end 5.115814 4.99999)
			(stroke
				(width 0.1524)
				(type default)
			)
			(layer "F.SilkS")
		)
		(fp_line
			(start 7.649972 -4.99999)
			(end -7.649972 -4.99999)
			(stroke
				(width 0.1)
				(type default)
			)
			(layer "F.Fab")
		)
		(fp_line
			(start -7.649972 -4.99999)
			(end -7.649972 4.99999)
			(stroke
				(width 0.1)
				(type default)
			)
			(layer "F.Fab")
		)
		(fp_line
			(start 7.649972 4.99999)
			(end 7.649972 -4.99999)
			(stroke
				(width 0.1)
				(type default)
			)
			(layer "F.Fab")
		)
		(fp_line
			(start -7.649972 4.99999)
			(end 7.649972 4.99999)
			(stroke
				(width 0.1)
				(type default)
			)
			(layer "F.Fab")
		)
		(pad "D" smd circle
			(at 2.15011 0 90)
			(size 0 0)
			(layers "F.Cu" "F.Mask" "F.Paste")
			(net "P52V_HS1")
		)
		(pad "G" smd rect
			(at -7.050024 -2.54)
			(size 1.3208 3.0988)
			(layers "F.Cu" "F.Mask" "F.Paste")
			(net "P52V_HS1_EN_DISCHARGE_N")
		)
		(pad "S" smd rect
			(at -7.050024 2.54)
			(size 1.3208 3.0988)
			(layers "F.Cu" "F.Mask" "F.Paste")
			(net "P52V_HS1_EN_DISCHARGE_VBE_R")
		)
		(zone
			(layer "F.Cu")
			(hatch none 0.5)
			(connect_pads
				(clearance 0)
			)
			(min_thickness 0.25)
			(keepout
				(tracks not_allowed)
				(vias allowed)
				(pads allowed)
				(copperpour not_allowed)
				(footprints allowed)
			)
			(placement
				(enabled no)
				(sheetname "")
			)
			(fill
				(thermal_gap 0.5)
				(thermal_bridge_width 0.5)
				(island_removal_mode 0)
			)
			(polygon
				(pts
					(xy 392.6586 -38.711378) (xy 392.6586 -25.884378) (xy 394.3858 -25.884378) (xy 394.3858 -28.094178)
					(xy 395.8082 -28.094178) (xy 395.8082 -25.884378) (xy 399.4658 -25.884378) (xy 399.4658 -28.094178)
					(xy 400.8882 -28.094178) (xy 400.8882 -25.884378) (xy 402.6154 -25.884378) (xy 402.6154 -38.711378)
					(xy 401.447 -38.711378) (xy 401.447 -32.513778) (xy 393.827 -32.513778) (xy 393.827 -38.711378)
				)
			)
		)
	)
)
